FILE_TYPE = CONNECTIVITY;
{Allegro Design Entry HDL 17.2-2016 S081 (4005846) 1/11/2022}
"PAGE_NUMBER" = 89;
0"NC";
1"M_E_CPU0_SA_CB<7:0>";
2"M_E_CPU0_SA_CA<6:0>";
3"M_E_CPU0_SB_CA<6:0>";
4"M_E_CPU0_SB_CB<7:0>";
5"M_E_CPU0_SA_DQ<31:0>";
6"M_E_CPU0_SB_DQ<31:0>";
7"M_E_CPU0_SA_DQS_DN<9:0>";
8"M_E_CPU0_SA_DQS_DP<9:0>";
9"M_E_CPU0_SB_DQS_DN<9:0>";
10"M_E_CPU0_SB_DQS_DP<9:0>";
11"GND\g";
12"GND\g";
13"P3V3_STBY\g";
14"P3V3_STBY\g";
15"I3C_SPD_DDRAF_CPU0_SDA";
16"I3C_SPD_DDRAF_CPU0_SCL";
17"I3C_SPD_DDRE_CPU0_SCL";
18"PWRGD_CHE_CPU0_DIMM";
19"PD_CHE_CPU0_DIMM_SAA";
20"TP_CHE_CPU0_DIMM_RFU_6";
21"M_E_CPU0_ALERT_N";
22"M_E_CPU0_SA_CS_N<0>";
23"M_E_CPU0_CLK_DP<0>";
24"M_E_CPU0_SA_CB<6>";
25"M_E_CPU0_SA_CB<5>";
26"GND\g";
27"GND\g";
28"P12V_MEM_1\g";
29"M_E_CPU0_SA_DQS_DP<3>";
30"M_E_CPU0_SA_DQ<19>";
31"M_E_CPU0_SA_DQS_DN<9>";
32"M_E_CPU0_SA_DQS_DP<9>";
33"M_E_CPU0_SB_DQS_DP<9>";
34"M_E_CPU0_SB_DQS_DN<9>";
35"M_E_CPU0_SA_DQS_DP<8>";
36"M_E_CPU0_SA_DQS_DN<8>";
37"M_E_CPU0_SB_DQS_DN<7>";
38"M_E_CPU0_SA_DQS_DP<7>";
39"M_E_CPU0_SB_DQS_DP<6>";
40"M_E_CPU0_SB_DQS_DN<6>";
41"M_E_CPU0_SA_DQS_DN<6>";
42"M_E_CPU0_SB_DQS_DP<5>";
43"M_E_CPU0_SB_DQS_DN<5>";
44"M_E_CPU0_SA_DQS_DP<5>";
45"M_E_CPU0_SA_DQS_DN<5>";
46"M_E_CPU0_SB_DQS_DP<4>";
47"M_E_CPU0_SB_DQS_DN<4>";
48"M_E_CPU0_SA_DQS_DP<4>";
49"M_E_CPU0_SA_DQS_DN<4>";
50"M_E_CPU0_SB_DQS_DP<3>";
51"M_E_CPU0_SB_DQS_DN<3>";
52"M_E_CPU0_SA_DQS_DN<3>";
53"M_E_CPU0_SB_DQS_DP<2>";
54"M_E_CPU0_SB_DQS_DN<2>";
55"M_E_CPU0_SA_DQS_DP<2>";
56"M_E_CPU0_SA_DQS_DN<2>";
57"M_E_CPU0_SB_DQS_DP<1>";
58"M_E_CPU0_SB_DQS_DN<1>";
59"M_E_CPU0_SA_DQS_DP<1>";
60"M_E_CPU0_SA_DQS_DN<1>";
61"M_E_CPU0_SB_DQS_DP<0>";
62"M_E_CPU0_SB_DQS_DN<0>";
63"M_E_CPU0_SA_DQS_DP<0>";
64"M_E_CPU0_SA_DQS_DN<0>";
65"M_E_CPU0_SB_DQS_DP<7>";
66"M_E_CPU0_SB_DQS_DN<8>";
67"M_E_CPU0_SB_DQS_DP<8>";
68"M_E_CPU0_SA_DQS_DP<6>";
69"M_E_CPU0_SA_DQS_DN<7>";
70"M_E_CPU0_SA_DQ<22>";
71"M_E_CPU0_SB_CA<4>";
72"M_E_CPU0_SA_CA<1>";
73"M_E_CPU0_SA_DQ<29>";
74"M_E_CPU0_SA_DQ<25>";
75"TP_CHE_CPU0_DIMM_RFU_0";
76"TP_CHE_CPU0_DIMM_RFU_1";
77"TP_CHE_CPU0_DIMM_RFU_2";
78"TP_CHE_CPU0_DIMM_RFU_3";
79"TP_CHE_CPU0_DIMM_RFU_4";
80"TP_CHE_CPU0_DIMM_RFU_5";
81"M_E_CPU0_RESET_N";
82"M_E_CPU0_SB_PAR";
83"M_E_CPU0_SA_PAR";
84"M_E_CPU0_SB_RSP<0>";
85"M_E_CPU0_SA_RSP<0>";
86"M_E_CPU0_SB_DQ<0>";
87"M_E_CPU0_SB_DQ<1>";
88"M_E_CPU0_SB_DQ<2>";
89"M_E_CPU0_SB_DQ<3>";
90"M_E_CPU0_SB_DQ<4>";
91"M_E_CPU0_SB_DQ<5>";
92"M_E_CPU0_SB_DQ<6>";
93"M_E_CPU0_SB_DQ<7>";
94"M_E_CPU0_SB_DQ<8>";
95"M_E_CPU0_SB_DQ<9>";
96"M_E_CPU0_SB_DQ<10>";
97"M_E_CPU0_SB_DQ<11>";
98"M_E_CPU0_SB_DQ<12>";
99"M_E_CPU0_SB_DQ<13>";
100"M_E_CPU0_SB_DQ<14>";
101"M_E_CPU0_SB_DQ<15>";
102"M_E_CPU0_SB_DQ<16>";
103"M_E_CPU0_SB_DQ<17>";
104"M_E_CPU0_SB_DQ<18>";
105"M_E_CPU0_SB_DQ<19>";
106"M_E_CPU0_SB_DQ<20>";
107"M_E_CPU0_SB_DQ<21>";
108"M_E_CPU0_SB_DQ<22>";
109"M_E_CPU0_SB_DQ<23>";
110"M_E_CPU0_SB_DQ<24>";
111"M_E_CPU0_SB_DQ<25>";
112"M_E_CPU0_SB_DQ<26>";
113"M_E_CPU0_SB_DQ<27>";
114"M_E_CPU0_SB_DQ<28>";
115"M_E_CPU0_SB_DQ<29>";
116"M_E_CPU0_SB_DQ<30>";
117"M_E_CPU0_SB_DQ<31>";
118"M_E_CPU0_SA_DQ<0>";
119"M_E_CPU0_SA_DQ<1>";
120"M_E_CPU0_SA_DQ<2>";
121"M_E_CPU0_SA_DQ<3>";
122"M_E_CPU0_SA_DQ<4>";
123"M_E_CPU0_SA_DQ<5>";
124"M_E_CPU0_SA_DQ<6>";
125"M_E_CPU0_SA_DQ<7>";
126"M_E_CPU0_SA_DQ<8>";
127"M_E_CPU0_SA_DQ<9>";
128"M_E_CPU0_SA_DQ<10>";
129"M_E_CPU0_SA_DQ<11>";
130"M_E_CPU0_SA_DQ<12>";
131"M_E_CPU0_SA_DQ<13>";
132"M_E_CPU0_SA_DQ<14>";
133"M_E_CPU0_SA_DQ<15>";
134"M_E_CPU0_SA_DQ<16>";
135"M_E_CPU0_SA_DQ<17>";
136"M_E_CPU0_SA_DQ<18>";
137"M_E_CPU0_SA_DQ<20>";
138"M_E_CPU0_SA_DQ<21>";
139"M_E_CPU0_SA_DQ<23>";
140"M_E_CPU0_SA_DQ<24>";
141"M_E_CPU0_SA_DQ<26>";
142"M_E_CPU0_SA_DQ<27>";
143"M_E_CPU0_SA_DQ<28>";
144"M_E_CPU0_SA_DQ<30>";
145"M_E_CPU0_SB_CS_N<1>";
146"M_E_CPU0_SA_CS_N<1>";
147"M_E_CPU0_SB_CS_N<0>";
148"M_E_CPU0_CLK_DN<0>";
149"M_E_CPU0_SB_CB<0>";
150"M_E_CPU0_SB_CB<1>";
151"M_E_CPU0_SB_CB<2>";
152"M_E_CPU0_SB_CB<3>";
153"M_E_CPU0_SB_CB<4>";
154"M_E_CPU0_SB_CB<5>";
155"M_E_CPU0_SB_CB<6>";
156"M_E_CPU0_SA_CB<0>";
157"M_E_CPU0_SA_CB<2>";
158"M_E_CPU0_SA_CB<3>";
159"M_E_CPU0_SB_CA<6>";
160"M_E_CPU0_SA_CA<6>";
161"M_E_CPU0_SB_CA<5>";
162"M_E_CPU0_SA_CA<5>";
163"M_E_CPU0_SA_CA<4>";
164"M_E_CPU0_SB_CA<3>";
165"M_E_CPU0_SA_CA<3>";
166"M_E_CPU0_SB_CA<2>";
167"M_E_CPU0_SA_CA<2>";
168"M_E_CPU0_SB_CA<1>";
169"M_E_CPU0_SB_CA<0>";
170"M_E_CPU0_SA_CA<0>";
171"M_E_CPU0_SB_CB<7>";
172"M_E_CPU0_SA_CB<1>";
173"M_E_CPU0_SA_CB<4>";
174"M_E_CPU0_SA_CB<7>";
175"M_E_CPU0_SA_DQ<31>";
176"PWRGD_CHAF_CPU0";
177"PD_CHE_CPU0_DIMM_SAA";
178"GND\g";
%"GND"
"1","(-2300,2175)","0","mstr_symbols","I150";
;
CDS_LIB"mstr_symbols"
SIZE"1B"
BODY_TYPE"PLUMBING"
VOLTAGE"0.0"
HDL_POWER"GND";
"A\NAC"26;
%"GND"
"1","(-500,2000)","0","mstr_symbols","I152";
;
SIZE"1B"
CDS_LIB"mstr_symbols"
BODY_TYPE"PLUMBING"
VOLTAGE"0.0"
HDL_POWER"GND";
"A\NAC"27;
%"VCC_CORE"
"1","(-8775,3650)","0","mstr_symbols","I177";
;
HDL_POWER"P3V3_STBY"
CDS_LIB"mstr_symbols"
VOLTAGE"3.3"
ROOM"PVCCINFAON_CPU0_CTRL";
"A"14;
%"TAP"
"1","(-7975,3425)","2","mstr_standard","I187";
;
CDS_LIB"mstr_standard"
BODY_TYPE"PLUMBING"
HDL_TAP"TRUE";
"B \NAC \NWC"4;
"S \NAC"
BN"1"150;
%"TAP"
"1","(-7975,3475)","2","mstr_standard","I188";
;
CDS_LIB"mstr_standard"
BODY_TYPE"PLUMBING"
HDL_TAP"TRUE";
"B \NAC \NWC"4;
"S \NAC"
BN"2"151;
%"TAP"
"1","(-7975,3375)","2","mstr_standard","I189";
;
CDS_LIB"mstr_standard"
BODY_TYPE"PLUMBING"
HDL_TAP"TRUE";
"B \NAC \NWC"4;
"S \NAC"
BN"0"149;
%"TAP"
"1","(-7975,3525)","2","mstr_standard","I190";
;
CDS_LIB"mstr_standard"
BODY_TYPE"PLUMBING"
HDL_TAP"TRUE";
"B \NAC \NWC"4;
"S \NAC"
BN"3"152;
%"TAP"
"1","(-7975,3575)","2","mstr_standard","I191";
;
CDS_LIB"mstr_standard"
BODY_TYPE"PLUMBING"
HDL_TAP"TRUE";
"B \NAC \NWC"4;
"S \NAC"
BN"4"153;
%"TAP"
"1","(-7975,3625)","2","mstr_standard","I192";
;
CDS_LIB"mstr_standard"
BODY_TYPE"PLUMBING"
HDL_TAP"TRUE";
"B \NAC \NWC"4;
"S \NAC"
BN"5"154;
%"TAP"
"1","(-7975,3725)","2","mstr_standard","I193";
;
CDS_LIB"mstr_standard"
BODY_TYPE"PLUMBING"
HDL_TAP"TRUE";
"B \NAC \NWC"4;
"S \NAC"
BN"7"171;
%"TAP"
"1","(-7975,3675)","2","mstr_standard","I194";
;
CDS_LIB"mstr_standard"
BODY_TYPE"PLUMBING"
HDL_TAP"TRUE";
"B \NAC \NWC"4;
"S \NAC"
BN"6"155;
%"TAP"
"1","(-7975,3925)","2","mstr_standard","I195";
;
CDS_LIB"mstr_standard"
BODY_TYPE"PLUMBING"
HDL_TAP"TRUE";
"B \NAC \NWC"1;
"S \NAC"
BN"2"157;
%"TAP"
"1","(-7975,3875)","2","mstr_standard","I196";
;
CDS_LIB"mstr_standard"
BODY_TYPE"PLUMBING"
HDL_TAP"TRUE";
"B \NAC \NWC"1;
"S \NAC"
BN"1"172;
%"TAP"
"1","(-7975,3825)","2","mstr_standard","I197";
;
CDS_LIB"mstr_standard"
BODY_TYPE"PLUMBING"
HDL_TAP"TRUE";
"B \NAC \NWC"1;
"S \NAC"
BN"0"156;
%"TAP"
"1","(-7975,3975)","2","mstr_standard","I198";
;
CDS_LIB"mstr_standard"
BODY_TYPE"PLUMBING"
HDL_TAP"TRUE";
"B \NAC \NWC"1;
"S \NAC"
BN"3"158;
%"TAP"
"1","(-7975,4025)","2","mstr_standard","I199";
;
CDS_LIB"mstr_standard"
BODY_TYPE"PLUMBING"
HDL_TAP"TRUE";
"B \NAC \NWC"1;
"S \NAC"
BN"4"173;
%"TAP"
"1","(-7975,4075)","2","mstr_standard","I200";
;
CDS_LIB"mstr_standard"
BODY_TYPE"PLUMBING"
HDL_TAP"TRUE";
"B \NAC \NWC"1;
"S \NAC"
BN"5"25;
%"TAP"
"1","(-7975,4125)","2","mstr_standard","I201";
;
CDS_LIB"mstr_standard"
BODY_TYPE"PLUMBING"
HDL_TAP"TRUE";
"B \NAC \NWC"1;
"S \NAC"
BN"6"24;
%"TAP"
"1","(-7975,4175)","2","mstr_standard","I202";
;
CDS_LIB"mstr_standard"
BODY_TYPE"PLUMBING"
HDL_TAP"TRUE";
"B \NAC \NWC"1;
"S \NAC"
BN"7"174;
%"TAP"
"1","(-7975,5025)","2","mstr_standard","I203";
;
CDS_LIB"mstr_standard"
BODY_TYPE"PLUMBING"
HDL_TAP"TRUE";
"B \NAC \NWC"3;
"S \NAC"
BN"3"164;
%"TAP"
"1","(-7975,4925)","2","mstr_standard","I204";
;
CDS_LIB"mstr_standard"
BODY_TYPE"PLUMBING"
HDL_TAP"TRUE";
"B \NAC \NWC"3;
"S \NAC"
BN"1"168;
%"TAP"
"1","(-7975,4875)","2","mstr_standard","I205";
;
CDS_LIB"mstr_standard"
BODY_TYPE"PLUMBING"
HDL_TAP"TRUE";
"B \NAC \NWC"3;
"S \NAC"
BN"0"169;
%"TAP"
"1","(-7975,4975)","2","mstr_standard","I206";
;
CDS_LIB"mstr_standard"
BODY_TYPE"PLUMBING"
HDL_TAP"TRUE";
"B \NAC \NWC"3;
"S \NAC"
BN"2"166;
%"TAP"
"1","(-6275,2425)","0","mstr_standard","I207";
;
CDS_LIB"mstr_standard"
BODY_TYPE"PLUMBING"
HDL_TAP"TRUE";
"B \NAC \NWC"6;
"S \NAC"
BN"1"87;
%"TAP"
"1","(-6275,2375)","0","mstr_standard","I208";
;
CDS_LIB"mstr_standard"
BODY_TYPE"PLUMBING"
HDL_TAP"TRUE";
"B \NAC \NWC"6;
"S \NAC"
BN"0"86;
%"TAP"
"1","(-6275,2475)","0","mstr_standard","I209";
;
CDS_LIB"mstr_standard"
BODY_TYPE"PLUMBING"
HDL_TAP"TRUE";
"B \NAC \NWC"6;
"S \NAC"
BN"2"88;
%"TAP"
"1","(-6275,2525)","0","mstr_standard","I210";
;
CDS_LIB"mstr_standard"
BODY_TYPE"PLUMBING"
HDL_TAP"TRUE";
"B \NAC \NWC"6;
"S \NAC"
BN"3"89;
%"TAP"
"1","(-6275,2575)","0","mstr_standard","I211";
;
CDS_LIB"mstr_standard"
BODY_TYPE"PLUMBING"
HDL_TAP"TRUE";
"B \NAC \NWC"6;
"S \NAC"
BN"4"90;
%"TAP"
"1","(-6275,2625)","0","mstr_standard","I212";
;
CDS_LIB"mstr_standard"
BODY_TYPE"PLUMBING"
HDL_TAP"TRUE";
"B \NAC \NWC"6;
"S \NAC"
BN"5"91;
%"TAP"
"1","(-6275,2725)","0","mstr_standard","I213";
;
CDS_LIB"mstr_standard"
BODY_TYPE"PLUMBING"
HDL_TAP"TRUE";
"B \NAC \NWC"6;
"S \NAC"
BN"7"93;
%"TAP"
"1","(-6275,2675)","0","mstr_standard","I214";
;
CDS_LIB"mstr_standard"
BODY_TYPE"PLUMBING"
HDL_TAP"TRUE";
"B \NAC \NWC"6;
"S \NAC"
BN"6"92;
%"TAP"
"1","(-6275,2775)","0","mstr_standard","I215";
;
CDS_LIB"mstr_standard"
BODY_TYPE"PLUMBING"
HDL_TAP"TRUE";
"B \NAC \NWC"6;
"S \NAC"
BN"8"94;
%"TAP"
"1","(-6275,2825)","0","mstr_standard","I216";
;
CDS_LIB"mstr_standard"
BODY_TYPE"PLUMBING"
HDL_TAP"TRUE";
"B \NAC \NWC"6;
"S \NAC"
BN"9"95;
%"TAP"
"1","(-6275,2875)","0","mstr_standard","I217";
;
CDS_LIB"mstr_standard"
BODY_TYPE"PLUMBING"
HDL_TAP"TRUE";
"B \NAC \NWC"6;
"S \NAC"
BN"10"96;
%"TAP"
"1","(-6275,2925)","0","mstr_standard","I218";
;
CDS_LIB"mstr_standard"
BODY_TYPE"PLUMBING"
HDL_TAP"TRUE";
"B \NAC \NWC"6;
"S \NAC"
BN"11"97;
%"TAP"
"1","(-6275,2975)","0","mstr_standard","I219";
;
CDS_LIB"mstr_standard"
BODY_TYPE"PLUMBING"
HDL_TAP"TRUE";
"B \NAC \NWC"6;
"S \NAC"
BN"12"98;
%"TAP"
"1","(-6275,3025)","0","mstr_standard","I220";
;
CDS_LIB"mstr_standard"
BODY_TYPE"PLUMBING"
HDL_TAP"TRUE";
"B \NAC \NWC"6;
"S \NAC"
BN"13"99;
%"TAP"
"1","(-6275,3125)","0","mstr_standard","I221";
;
CDS_LIB"mstr_standard"
BODY_TYPE"PLUMBING"
HDL_TAP"TRUE";
"B \NAC \NWC"6;
"S \NAC"
BN"15"101;
%"TAP"
"1","(-6275,3075)","0","mstr_standard","I222";
;
CDS_LIB"mstr_standard"
BODY_TYPE"PLUMBING"
HDL_TAP"TRUE";
"B \NAC \NWC"6;
"S \NAC"
BN"14"100;
%"TAP"
"1","(-6275,3275)","0","mstr_standard","I223";
;
CDS_LIB"mstr_standard"
BODY_TYPE"PLUMBING"
HDL_TAP"TRUE";
"B \NAC \NWC"6;
"S \NAC"
BN"18"104;
%"TAP"
"1","(-6275,3225)","0","mstr_standard","I224";
;
CDS_LIB"mstr_standard"
BODY_TYPE"PLUMBING"
HDL_TAP"TRUE";
"B \NAC \NWC"6;
"S \NAC"
BN"17"103;
%"TAP"
"1","(-6275,3175)","0","mstr_standard","I225";
;
CDS_LIB"mstr_standard"
BODY_TYPE"PLUMBING"
HDL_TAP"TRUE";
"B \NAC \NWC"6;
"S \NAC"
BN"16"102;
%"TAP"
"1","(-6275,3425)","0","mstr_standard","I226";
;
CDS_LIB"mstr_standard"
BODY_TYPE"PLUMBING"
HDL_TAP"TRUE";
"B \NAC \NWC"6;
"S \NAC"
BN"21"107;
%"TAP"
"1","(-6275,3475)","0","mstr_standard","I227";
;
CDS_LIB"mstr_standard"
BODY_TYPE"PLUMBING"
HDL_TAP"TRUE";
"B \NAC \NWC"6;
"S \NAC"
BN"22"108;
%"TAP"
"1","(-6275,3375)","0","mstr_standard","I228";
;
CDS_LIB"mstr_standard"
BODY_TYPE"PLUMBING"
HDL_TAP"TRUE";
"B \NAC \NWC"6;
"S \NAC"
BN"20"106;
%"TAP"
"1","(-6275,3525)","0","mstr_standard","I229";
;
CDS_LIB"mstr_standard"
BODY_TYPE"PLUMBING"
HDL_TAP"TRUE";
"B \NAC \NWC"6;
"S \NAC"
BN"23"109;
%"TAP"
"1","(-6275,3325)","0","mstr_standard","I230";
;
CDS_LIB"mstr_standard"
BODY_TYPE"PLUMBING"
HDL_TAP"TRUE";
"B \NAC \NWC"6;
"S \NAC"
BN"19"105;
%"TAP"
"1","(-6275,3675)","0","mstr_standard","I231";
;
CDS_LIB"mstr_standard"
BODY_TYPE"PLUMBING"
HDL_TAP"TRUE";
"B \NAC \NWC"6;
"S \NAC"
BN"26"112;
%"TAP"
"1","(-6275,3725)","0","mstr_standard","I232";
;
CDS_LIB"mstr_standard"
BODY_TYPE"PLUMBING"
HDL_TAP"TRUE";
"B \NAC \NWC"6;
"S \NAC"
BN"27"113;
%"TAP"
"1","(-6275,3625)","0","mstr_standard","I233";
;
CDS_LIB"mstr_standard"
BODY_TYPE"PLUMBING"
HDL_TAP"TRUE";
"B \NAC \NWC"6;
"S \NAC"
BN"25"111;
%"TAP"
"1","(-6275,3775)","0","mstr_standard","I234";
;
CDS_LIB"mstr_standard"
BODY_TYPE"PLUMBING"
HDL_TAP"TRUE";
"B \NAC \NWC"6;
"S \NAC"
BN"28"114;
%"TAP"
"1","(-6275,3575)","0","mstr_standard","I235";
;
CDS_LIB"mstr_standard"
BODY_TYPE"PLUMBING"
HDL_TAP"TRUE";
"B \NAC \NWC"6;
"S \NAC"
BN"24"110;
%"TAP"
"1","(-6275,4025)","0","mstr_standard","I236";
;
CDS_LIB"mstr_standard"
BODY_TYPE"PLUMBING"
HDL_TAP"TRUE";
"B \NAC \NWC"5;
"S \NAC"
BN"0"118;
%"TAP"
"1","(-6275,3875)","0","mstr_standard","I237";
;
CDS_LIB"mstr_standard"
BODY_TYPE"PLUMBING"
HDL_TAP"TRUE";
"B \NAC \NWC"6;
"S \NAC"
BN"30"116;
%"TAP"
"1","(-6275,3925)","0","mstr_standard","I238";
;
CDS_LIB"mstr_standard"
BODY_TYPE"PLUMBING"
HDL_TAP"TRUE";
"B \NAC \NWC"6;
"S \NAC"
BN"31"117;
%"TAP"
"1","(-6275,3825)","0","mstr_standard","I239";
;
CDS_LIB"mstr_standard"
BODY_TYPE"PLUMBING"
HDL_TAP"TRUE";
"B \NAC \NWC"6;
"S \NAC"
BN"29"115;
%"TAP"
"1","(-6275,4125)","0","mstr_standard","I240";
;
CDS_LIB"mstr_standard"
BODY_TYPE"PLUMBING"
HDL_TAP"TRUE";
"B \NAC \NWC"5;
"S \NAC"
BN"2"120;
%"TAP"
"1","(-6275,4075)","0","mstr_standard","I241";
;
CDS_LIB"mstr_standard"
BODY_TYPE"PLUMBING"
HDL_TAP"TRUE";
"B \NAC \NWC"5;
"S \NAC"
BN"1"119;
%"TAP"
"1","(-6275,4175)","0","mstr_standard","I242";
;
CDS_LIB"mstr_standard"
BODY_TYPE"PLUMBING"
HDL_TAP"TRUE";
"B \NAC \NWC"5;
"S \NAC"
BN"3"121;
%"TAP"
"1","(-6275,4225)","0","mstr_standard","I243";
;
CDS_LIB"mstr_standard"
BODY_TYPE"PLUMBING"
HDL_TAP"TRUE";
"B \NAC \NWC"5;
"S \NAC"
BN"4"122;
%"TAP"
"1","(-6275,4275)","0","mstr_standard","I244";
;
CDS_LIB"mstr_standard"
BODY_TYPE"PLUMBING"
HDL_TAP"TRUE";
"B \NAC \NWC"5;
"S \NAC"
BN"5"123;
%"TAP"
"1","(-6275,4375)","0","mstr_standard","I245";
;
CDS_LIB"mstr_standard"
BODY_TYPE"PLUMBING"
HDL_TAP"TRUE";
"B \NAC \NWC"5;
"S \NAC"
BN"7"125;
%"TAP"
"1","(-6275,4325)","0","mstr_standard","I246";
;
CDS_LIB"mstr_standard"
BODY_TYPE"PLUMBING"
HDL_TAP"TRUE";
"B \NAC \NWC"5;
"S \NAC"
BN"6"124;
%"TAP"
"1","(-6275,4425)","0","mstr_standard","I247";
;
CDS_LIB"mstr_standard"
BODY_TYPE"PLUMBING"
HDL_TAP"TRUE";
"B \NAC \NWC"5;
"S \NAC"
BN"8"126;
%"TAP"
"1","(-6275,4475)","0","mstr_standard","I248";
;
CDS_LIB"mstr_standard"
BODY_TYPE"PLUMBING"
HDL_TAP"TRUE";
"B \NAC \NWC"5;
"S \NAC"
BN"9"127;
%"TAP"
"1","(-6275,4525)","0","mstr_standard","I249";
;
CDS_LIB"mstr_standard"
BODY_TYPE"PLUMBING"
HDL_TAP"TRUE";
"B \NAC \NWC"5;
"S \NAC"
BN"10"128;
%"TAP"
"1","(-6275,4725)","0","mstr_standard","I250";
;
CDS_LIB"mstr_standard"
BODY_TYPE"PLUMBING"
HDL_TAP"TRUE";
"B \NAC \NWC"5;
"S \NAC"
BN"14"132;
%"TAP"
"1","(-6275,4775)","0","mstr_standard","I251";
;
CDS_LIB"mstr_standard"
BODY_TYPE"PLUMBING"
HDL_TAP"TRUE";
"B \NAC \NWC"5;
"S \NAC"
BN"15"133;
%"TAP"
"1","(-6275,4675)","0","mstr_standard","I252";
;
CDS_LIB"mstr_standard"
BODY_TYPE"PLUMBING"
HDL_TAP"TRUE";
"B \NAC \NWC"5;
"S \NAC"
BN"13"131;
%"TAP"
"1","(-6275,4625)","0","mstr_standard","I253";
;
CDS_LIB"mstr_standard"
BODY_TYPE"PLUMBING"
HDL_TAP"TRUE";
"B \NAC \NWC"5;
"S \NAC"
BN"12"130;
%"TAP"
"1","(-6275,4575)","0","mstr_standard","I254";
;
CDS_LIB"mstr_standard"
BODY_TYPE"PLUMBING"
HDL_TAP"TRUE";
"B \NAC \NWC"5;
"S \NAC"
BN"11"129;
%"TAP"
"1","(-6275,4875)","0","mstr_standard","I255";
;
CDS_LIB"mstr_standard"
BODY_TYPE"PLUMBING"
HDL_TAP"TRUE";
"B \NAC \NWC"5;
"S \NAC"
BN"17"135;
%"TAP"
"1","(-6275,4925)","0","mstr_standard","I256";
;
CDS_LIB"mstr_standard"
BODY_TYPE"PLUMBING"
HDL_TAP"TRUE";
"B \NAC \NWC"5;
"S \NAC"
BN"18"136;
%"TAP"
"1","(-6275,4825)","0","mstr_standard","I257";
;
CDS_LIB"mstr_standard"
BODY_TYPE"PLUMBING"
HDL_TAP"TRUE";
"B \NAC \NWC"5;
"S \NAC"
BN"16"134;
%"TAP"
"1","(-6275,5025)","0","mstr_standard","I258";
;
CDS_LIB"mstr_standard"
BODY_TYPE"PLUMBING"
HDL_TAP"TRUE";
"B \NAC \NWC"5;
"S \NAC"
BN"20"137;
%"TAP"
"1","(-6275,4975)","0","mstr_standard","I259";
;
CDS_LIB"mstr_standard"
BODY_TYPE"PLUMBING"
HDL_TAP"TRUE";
"B \NAC \NWC"5;
"S \NAC"
BN"19"30;
%"TAP"
"1","(-7975,5175)","2","mstr_standard","I263";
;
CDS_LIB"mstr_standard"
BODY_TYPE"PLUMBING"
HDL_TAP"TRUE";
"B \NAC \NWC"3;
"S \NAC"
BN"6"159;
%"TAP"
"1","(-7975,5075)","2","mstr_standard","I264";
;
CDS_LIB"mstr_standard"
BODY_TYPE"PLUMBING"
HDL_TAP"TRUE";
"B \NAC \NWC"3;
"S \NAC"
BN"4"71;
%"TAP"
"1","(-7975,5125)","2","mstr_standard","I265";
;
CDS_LIB"mstr_standard"
BODY_TYPE"PLUMBING"
HDL_TAP"TRUE";
"B \NAC \NWC"3;
"S \NAC"
BN"5"161;
%"TAP"
"1","(-7975,5275)","2","mstr_standard","I266";
;
CDS_LIB"mstr_standard"
BODY_TYPE"PLUMBING"
HDL_TAP"TRUE";
"B \NAC \NWC"2;
"S \NAC"
BN"0"170;
%"TAP"
"1","(-7975,5325)","2","mstr_standard","I267";
;
CDS_LIB"mstr_standard"
BODY_TYPE"PLUMBING"
HDL_TAP"TRUE";
"B \NAC \NWC"2;
"S \NAC"
BN"1"72;
%"TAP"
"1","(-7975,5375)","2","mstr_standard","I268";
;
CDS_LIB"mstr_standard"
BODY_TYPE"PLUMBING"
HDL_TAP"TRUE";
"B \NAC \NWC"2;
"S \NAC"
BN"2"167;
%"TAP"
"1","(-7975,5425)","2","mstr_standard","I269";
;
CDS_LIB"mstr_standard"
BODY_TYPE"PLUMBING"
HDL_TAP"TRUE";
"B \NAC \NWC"2;
"S \NAC"
BN"3"165;
%"TAP"
"1","(-7975,5525)","2","mstr_standard","I270";
;
CDS_LIB"mstr_standard"
BODY_TYPE"PLUMBING"
HDL_TAP"TRUE";
"B \NAC \NWC"2;
"S \NAC"
BN"5"162;
%"TAP"
"1","(-7975,5475)","2","mstr_standard","I271";
;
CDS_LIB"mstr_standard"
BODY_TYPE"PLUMBING"
HDL_TAP"TRUE";
"B \NAC \NWC"2;
"S \NAC"
BN"4"163;
%"TAP"
"1","(-7975,5575)","2","mstr_standard","I272";
;
CDS_LIB"mstr_standard"
BODY_TYPE"PLUMBING"
HDL_TAP"TRUE";
"B \NAC \NWC"2;
"S \NAC"
BN"6"160;
%"TAP"
"1","(-6275,5175)","0","mstr_standard","I273";
;
CDS_LIB"mstr_standard"
BODY_TYPE"PLUMBING"
HDL_TAP"TRUE";
"B \NAC \NWC"5;
"S \NAC"
BN"23"139;
%"TAP"
"1","(-6275,5075)","0","mstr_standard","I274";
;
CDS_LIB"mstr_standard"
BODY_TYPE"PLUMBING"
HDL_TAP"TRUE";
"B \NAC \NWC"5;
"S \NAC"
BN"21"138;
%"TAP"
"1","(-6275,5125)","0","mstr_standard","I275";
;
CDS_LIB"mstr_standard"
BODY_TYPE"PLUMBING"
HDL_TAP"TRUE";
"B \NAC \NWC"5;
"S \NAC"
BN"22"70;
%"TAP"
"1","(-6275,5225)","0","mstr_standard","I276";
;
CDS_LIB"mstr_standard"
BODY_TYPE"PLUMBING"
HDL_TAP"TRUE";
"B \NAC \NWC"5;
"S \NAC"
BN"24"140;
%"TAP"
"1","(-6275,5275)","0","mstr_standard","I277";
;
CDS_LIB"mstr_standard"
BODY_TYPE"PLUMBING"
HDL_TAP"TRUE";
"B \NAC \NWC"5;
"S \NAC"
BN"25"74;
%"TAP"
"1","(-6275,5325)","0","mstr_standard","I278";
;
CDS_LIB"mstr_standard"
BODY_TYPE"PLUMBING"
HDL_TAP"TRUE";
"B \NAC \NWC"5;
"S \NAC"
BN"26"141;
%"TAP"
"1","(-6275,5575)","0","mstr_standard","I279";
;
CDS_LIB"mstr_standard"
BODY_TYPE"PLUMBING"
HDL_TAP"TRUE";
"B \NAC \NWC"5;
"S \NAC"
BN"31"175;
%"TAP"
"1","(-6275,5375)","0","mstr_standard","I280";
;
CDS_LIB"mstr_standard"
BODY_TYPE"PLUMBING"
HDL_TAP"TRUE";
"B \NAC \NWC"5;
"S \NAC"
BN"27"142;
%"TAP"
"1","(-6275,5425)","0","mstr_standard","I281";
;
CDS_LIB"mstr_standard"
BODY_TYPE"PLUMBING"
HDL_TAP"TRUE";
"B \NAC \NWC"5;
"S \NAC"
BN"28"143;
%"TAP"
"1","(-6275,5525)","0","mstr_standard","I282";
;
CDS_LIB"mstr_standard"
BODY_TYPE"PLUMBING"
HDL_TAP"TRUE";
"B \NAC \NWC"5;
"S \NAC"
BN"30"144;
%"TAP"
"1","(-6275,5475)","0","mstr_standard","I283";
;
CDS_LIB"mstr_standard"
BODY_TYPE"PLUMBING"
HDL_TAP"TRUE";
"B \NAC \NWC"5;
"S \NAC"
BN"29"73;
%"Q_RES"
"2","(-6650,1425)","0","pure_quanta","I331";
;
LOCATION"R5"
SEC"1"
WATTAGE"1/16W"
MATERIAL"CHIP"
TOLERANCE"1%"
VALUE"54.9K"
PART_NUMBER"TMP_QCS35492FB14"
PACK_TYPE"0402LF"
BOM_COST"MEM"
CDS_LIB"pure_quanta"
SEC_TYPE"0402LF";
"A"
$PN"1"
XNET_PINS"3"177;
"B"
$PN"2"
XNET_PINS"2"11;
%"GND"
"1","(-6650,1200)","0","mstr_symbols","I332";
;
SIZE"1B"
CDS_LIB"mstr_symbols"
BOM_COST"MEM"
BODY_TYPE"PLUMBING"
VOLTAGE"0.0"
HDL_POWER"GND";
"A\NAC"11;
%"SCONN288_DDR506112002KQ"
"1","(-7125,3825)","0","pure_quanta","I348";
;
LOCATION"J21"
$SEC"1"
CDS_SEC"1"
PART_TYPE"SMLF"
VALUE"SCONN288_DDR506112002KQ"
MATERIAL"IO"
PART_NUMBER"DFHST8FS479"
CDS_LMAN_SYM_OUTLINE"-450,1900,450,-1850"
NEEDS_NO_SIZE"TRUE"
CDS_LIB"pure_quanta";
"PWR_GOOD||FAIL_N"
$PN"147"18;
"DQ31_A"
$PN"194"175;
"CB7_A"
$PN"205"174;
"CB4_A"
$PN"58"173;
"CB1_A"
$PN"53"172;
"CB7_B"
$PN"236"171;
"ALERT_N \B"
$PN"62"21;
"CA0_A"
$PN"66"170;
"CA0_B"
$PN"76"169;
"CA1_A"
$PN"211"72;
"CA1_B"
$PN"221"168;
"CA2_A"
$PN"68"167;
"CA2_B"
$PN"78"166;
"CA3_A"
$PN"213"165;
"CA3_B"
$PN"223"164;
"CA4_A"
$PN"70"163;
"CA4_B"
$PN"80"71;
"CA5_A"
$PN"215"162;
"CA5_B"
$PN"225"161;
"CA6_A"
$PN"72"160;
"CA6_B"
$PN"82"159;
"CB6_A"
$PN"203"24;
"CB5_A"
$PN"60"25;
"CB3_A"
$PN"198"158;
"CB2_A"
$PN"196"157;
"CB0_A"
$PN"51"156;
"CB6_B"
$PN"234"155;
"CB5_B"
$PN"91"154;
"CB4_B"
$PN"89"153;
"CB3_B"
$PN"243"152;
"CB2_B"
$PN"241"151;
"CB1_B"
$PN"98"150;
"CB0_B"
$PN"96"149;
"CK_C \B"
$PN"218"148;
"CK_T"
$PN"217"23;
"CS0_A_N"
$PN"64"22;
"CS0_B_N"
$PN"84"147;
"CS1_A_N"
$PN"209"146;
"CS1_B_N"
$PN"229"145;
"DQ30_A"
$PN"192"144;
"DQ29_A"
$PN"49"73;
"DQ28_A"
$PN"47"143;
"DQ27_A"
$PN"187"142;
"DQ26_A"
$PN"185"141;
"DQ25_A"
$PN"42"74;
"DQ24_A"
$PN"40"140;
"DQ23_A"
$PN"183"139;
"DQ22_A"
$PN"181"70;
"DQ21_A"
$PN"38"138;
"DQ20_A"
$PN"36"137;
"DQ19_A"
$PN"176"30;
"DQ18_A"
$PN"174"136;
"DQ17_A"
$PN"31"135;
"DQ16_A"
$PN"29"134;
"DQ15_A"
$PN"172"133;
"DQ14_A"
$PN"170"132;
"DQ13_A"
$PN"27"131;
"DQ12_A"
$PN"25"130;
"DQ11_A"
$PN"165"129;
"DQ10_A"
$PN"163"128;
"DQ9_A"
$PN"20"127;
"DQ8_A"
$PN"18"126;
"DQ7_A"
$PN"161"125;
"DQ6_A"
$PN"159"124;
"DQ5_A"
$PN"16"123;
"DQ4_A"
$PN"14"122;
"DQ3_A"
$PN"154"121;
"DQ2_A"
$PN"152"120;
"DQ1_A"
$PN"9"119;
"DQ0_A"
$PN"7"118;
"DQ31_B"
$PN"287"117;
"DQ30_B"
$PN"285"116;
"DQ29_B"
$PN"142"115;
"DQ28_B"
$PN"140"114;
"DQ27_B"
$PN"280"113;
"DQ26_B"
$PN"278"112;
"DQ25_B"
$PN"135"111;
"DQ24_B"
$PN"133"110;
"DQ23_B"
$PN"276"109;
"DQ22_B"
$PN"274"108;
"DQ21_B"
$PN"131"107;
"DQ20_B"
$PN"129"106;
"DQ19_B"
$PN"269"105;
"DQ18_B"
$PN"267"104;
"DQ17_B"
$PN"124"103;
"DQ16_B"
$PN"122"102;
"DQ15_B"
$PN"265"101;
"DQ14_B"
$PN"263"100;
"DQ13_B"
$PN"120"99;
"DQ12_B"
$PN"118"98;
"DQ11_B"
$PN"258"97;
"DQ10_B"
$PN"256"96;
"DQ9_B"
$PN"113"95;
"DQ8_B"
$PN"111"94;
"DQ7_B"
$PN"254"93;
"DQ6_B"
$PN"252"92;
"DQ5_B"
$PN"109"91;
"DQ4_B"
$PN"107"90;
"DQ3_B"
$PN"247"89;
"DQ2_B"
$PN"245"88;
"DQ1_B"
$PN"102"87;
"DQ0_B"
$PN"100"86;
"HAS"
$PN"148"19;
"HSCL"
$PN"4"17;
"HSDA"
$PN"5"15;
"LBD||RSP_A_N"
$PN"86"85;
"LBS||RSP_B_N"
$PN"87"84;
"PAR_A"
$PN"74"83;
"PAR_B"
$PN"227"82;
"RESET_N \B"
$PN"207"81;
"RFU6"
$PN"232"20;
"RFU5"
$PN"231"80;
"RFU4"
$PN"220"79;
"RFU3"
$PN"150"78;
"RFU2"
$PN"149"77;
"RFU1"
$PN"144"76;
"RFU0"
$PN"2"75;
"VIN_MGMT"
$PN"3"14;
%"SCONN288_DDR506112002KQ"
"3","(-1400,3925)","0","pure_quanta","I350";
;
LOCATION"J21"
$SEC"3"
CDS_SEC"3"
PART_TYPE"SMLF"
VALUE"SCONN288_DDR506112002KQ"
MATERIAL"IO"
PART_NUMBER"DFHST8FS479"
CDS_LMAN_SYM_OUTLINE"-450,1800,450,-1750"
NEEDS_NO_SIZE"TRUE"
CDS_LIB"pure_quanta";
"G3"
$PN"G3"27;
"G2"
$PN"G2"27;
"G1"
$PN"G1"27;
"VSS62"
$PN"141"27;
"VSS61"
$PN"139"27;
"VSS60"
$PN"136"27;
"VSS58"
$PN"132"27;
"VSS104"
$PN"240"26;
"VSS102"
$PN"235"26;
"VSS100"
$PN"230"26;
"VIN_BULK2"
$PN"146"28;
"VIN_BULK1"
$PN"145"28;
"VIN_BULK0"
$PN"1"28;
"VSS126"
$PN"288"26;
"VSS125"
$PN"286"26;
"VSS124"
$PN"284"26;
"VSS123"
$PN"281"26;
"VSS122"
$PN"279"26;
"VSS121"
$PN"277"26;
"VSS120"
$PN"275"26;
"VSS119"
$PN"273"26;
"VSS118"
$PN"270"26;
"VSS117"
$PN"268"26;
"VSS116"
$PN"266"26;
"VSS115"
$PN"264"26;
"VSS114"
$PN"262"26;
"VSS113"
$PN"259"26;
"VSS112"
$PN"257"26;
"VSS111"
$PN"255"26;
"VSS110"
$PN"253"26;
"VSS109"
$PN"251"26;
"VSS108"
$PN"248"26;
"VSS107"
$PN"246"26;
"VSS106"
$PN"244"26;
"VSS105"
$PN"242"26;
"VSS103"
$PN"237"26;
"VSS101"
$PN"233"26;
"VSS99"
$PN"228"26;
"VSS98"
$PN"226"26;
"VSS97"
$PN"224"26;
"VSS96"
$PN"222"26;
"VSS95"
$PN"219"26;
"VSS94"
$PN"216"26;
"VSS93"
$PN"214"26;
"VSS92"
$PN"212"26;
"VSS91"
$PN"210"26;
"VSS90"
$PN"208"26;
"VSS89"
$PN"206"26;
"VSS88"
$PN"204"26;
"VSS87"
$PN"202"26;
"VSS86"
$PN"199"26;
"VSS85"
$PN"197"26;
"VSS84"
$PN"195"26;
"VSS83"
$PN"193"26;
"VSS82"
$PN"191"26;
"VSS81"
$PN"188"26;
"VSS80"
$PN"186"26;
"VSS79"
$PN"184"26;
"VSS78"
$PN"182"26;
"VSS77"
$PN"180"26;
"VSS76"
$PN"177"26;
"VSS75"
$PN"175"26;
"VSS74"
$PN"173"26;
"VSS73"
$PN"171"26;
"VSS72"
$PN"169"26;
"VSS71"
$PN"166"26;
"VSS70"
$PN"164"26;
"VSS69"
$PN"162"26;
"VSS68"
$PN"160"26;
"VSS67"
$PN"158"26;
"VSS66"
$PN"155"26;
"VSS65"
$PN"153"26;
"VSS64"
$PN"151"26;
"VSS63"
$PN"143"27;
"VSS59"
$PN"134"27;
"VSS57"
$PN"130"27;
"VSS56"
$PN"128"27;
"VSS55"
$PN"125"27;
"VSS54"
$PN"123"27;
"VSS53"
$PN"121"27;
"VSS52"
$PN"119"27;
"VSS51"
$PN"117"27;
"VSS50"
$PN"114"27;
"VSS49"
$PN"112"27;
"VSS48"
$PN"110"27;
"VSS47"
$PN"108"27;
"VSS46"
$PN"106"27;
"VSS45"
$PN"103"27;
"VSS44"
$PN"101"27;
"VSS43"
$PN"99"27;
"VSS42"
$PN"97"27;
"VSS41"
$PN"95"27;
"VSS40"
$PN"92"27;
"VSS39"
$PN"90"27;
"VSS38"
$PN"88"27;
"VSS37"
$PN"85"27;
"VSS36"
$PN"83"27;
"VSS35"
$PN"81"27;
"VSS34"
$PN"79"27;
"VSS33"
$PN"77"27;
"VSS32"
$PN"75"27;
"VSS31"
$PN"73"27;
"VSS30"
$PN"71"27;
"VSS29"
$PN"69"27;
"VSS28"
$PN"67"27;
"VSS27"
$PN"65"27;
"VSS26"
$PN"63"27;
"VSS25"
$PN"61"27;
"VSS24"
$PN"59"27;
"VSS23"
$PN"57"27;
"VSS22"
$PN"54"27;
"VSS21"
$PN"52"27;
"VSS20"
$PN"50"27;
"VSS19"
$PN"48"27;
"VSS18"
$PN"46"27;
"VSS17"
$PN"43"27;
"VSS16"
$PN"41"27;
"VSS15"
$PN"39"27;
"VSS14"
$PN"37"27;
"VSS13"
$PN"35"27;
"VSS12"
$PN"32"27;
"VSS11"
$PN"30"27;
"VSS10"
$PN"28"27;
"VSS9"
$PN"26"27;
"VSS8"
$PN"24"27;
"VSS7"
$PN"21"27;
"VSS6"
$PN"19"27;
"VSS5"
$PN"17"27;
"VSS4"
$PN"15"27;
"VSS3"
$PN"13"27;
"VSS2"
$PN"10"27;
"VSS1"
$PN"8"27;
"VSS0"
$PN"6"27;
%"GND"
"1","(-8875,3175)","0","mstr_symbols","I359";
;
BOM_COST"MEM"
SIZE"1B"
CDS_LIB"mstr_symbols"
BODY_TYPE"PLUMBING"
VOLTAGE"0"
ROOM"MEM_EFGH_DECOUPLING_CAPS"
HDL_POWER"GND";
"A\NAC"12;
%"Q_CAP"
"1","(-8875,3400)","2","pure_quanta","I360";
;
LOCATION"C104"
$SEC"1"
CDS_SEC"1"
VALUE"0.1UF"
VOLTAGE"25V"
MATERIAL"X7R"
TOLERANCE"10%"
PACK_TYPE"0402"
PART_NUMBER"CH4104K1B00"
BOM_COST"MEM"
CDS_LIB"pure_quanta"
ROOM"MEM_CH_A_CPU0_DIMM1";
"B"
$PN"2"12;
"A"
$PN"1"14;
%"Q_RES"
"1","(-8725,2325)","2","pure_quanta","I362";
;
LOCATION"R295"
$SEC"1"
CDS_SEC"1"
VALUE"0"
CDS_LIB"pure_quanta"
BOM_COST"MEM"
WATTAGE"1/16W"
MATERIAL"CHIP"
TOLERANCE"5%"
PART_NUMBER"CS00002JB38"
PACK_TYPE"0402LF"
ROOM"RST_CPU0_PLD_TO_DIMM";
"B"
$PN"2"176;
"A"
$PN"1"18;
%"VCC_CORE"
"1","(-8600,2650)","0","mstr_symbols","I363";
;
HDL_POWER"P3V3_STBY"
CDS_LIB"mstr_symbols"
VOLTAGE"3.3"
ROOM"PVCCINFAON_CPU0_CTRL";
"A"13;
%"Q_RES"
"2","(-8600,2475)","0","pure_quanta","I364";
;
LOCATION"R93"
$SEC"1"
CDS_SEC"1"
WATTAGE"1/16W"
MATERIAL"EMPTY"
TOLERANCE"5%"
VALUE"1K"
PACK_TYPE"0402LF"
CDS_LIB"pure_quanta"
BOM_COST"MEM"
PART_NUMBER"TMP_QCS21002JB34"
ROOM"MEM_CH_A_CPU0_DIMM1";
"A"
$PN"1"13;
"B"
$PN"2"18;
%"TAP"
"1","(-3475,4625)","0","mstr_standard","I368";
;
CDS_LIB"mstr_standard"
BODY_TYPE"PLUMBING"
HDL_TAP"TRUE";
"B \NAC \NWC"7;
"S \NAC"
BN"9"31;
%"TAP"
"1","(-3675,4575)","0","mstr_standard","I369";
;
CDS_LIB"mstr_standard"
BODY_TYPE"PLUMBING"
HDL_TAP"TRUE";
"B \NAC \NWC"8;
"S \NAC"
BN"8"35;
%"TAP"
"1","(-3675,4675)","0","mstr_standard","I370";
;
CDS_LIB"mstr_standard"
BODY_TYPE"PLUMBING"
HDL_TAP"TRUE";
"B \NAC \NWC"8;
"S \NAC"
BN"9"32;
%"TAP"
"1","(-3475,4525)","0","mstr_standard","I371";
;
CDS_LIB"mstr_standard"
BODY_TYPE"PLUMBING"
HDL_TAP"TRUE";
"B \NAC \NWC"7;
"S \NAC"
BN"8"36;
%"TAP"
"1","(-3475,4325)","0","mstr_standard","I372";
;
CDS_LIB"mstr_standard"
BODY_TYPE"PLUMBING"
HDL_TAP"TRUE";
"B \NAC \NWC"7;
"S \NAC"
BN"6"41;
%"TAP"
"1","(-3475,4425)","0","mstr_standard","I373";
;
CDS_LIB"mstr_standard"
BODY_TYPE"PLUMBING"
HDL_TAP"TRUE";
"B \NAC \NWC"7;
"S \NAC"
BN"7"69;
%"TAP"
"1","(-3675,4475)","0","mstr_standard","I374";
;
CDS_LIB"mstr_standard"
BODY_TYPE"PLUMBING"
HDL_TAP"TRUE";
"B \NAC \NWC"8;
"S \NAC"
BN"7"38;
%"TAP"
"1","(-3675,4375)","0","mstr_standard","I375";
;
CDS_LIB"mstr_standard"
BODY_TYPE"PLUMBING"
HDL_TAP"TRUE";
"B \NAC \NWC"8;
"S \NAC"
BN"6"68;
%"TAP"
"1","(-3475,4125)","0","mstr_standard","I378";
;
CDS_LIB"mstr_standard"
BODY_TYPE"PLUMBING"
HDL_TAP"TRUE";
"B \NAC \NWC"7;
"S \NAC"
BN"4"49;
%"TAP"
"1","(-3475,4225)","0","mstr_standard","I379";
;
CDS_LIB"mstr_standard"
BODY_TYPE"PLUMBING"
HDL_TAP"TRUE";
"B \NAC \NWC"7;
"S \NAC"
BN"5"45;
%"TAP"
"1","(-3675,4175)","0","mstr_standard","I380";
;
CDS_LIB"mstr_standard"
BODY_TYPE"PLUMBING"
HDL_TAP"TRUE";
"B \NAC \NWC"8;
"S \NAC"
BN"4"48;
%"TAP"
"1","(-3675,4275)","0","mstr_standard","I381";
;
CDS_LIB"mstr_standard"
BODY_TYPE"PLUMBING"
HDL_TAP"TRUE";
"B \NAC \NWC"8;
"S \NAC"
BN"5"44;
%"TAP"
"1","(-3675,4075)","0","mstr_standard","I382";
;
CDS_LIB"mstr_standard"
BODY_TYPE"PLUMBING"
HDL_TAP"TRUE";
"B \NAC \NWC"8;
"S \NAC"
BN"3"29;
%"TAP"
"1","(-3475,3925)","0","mstr_standard","I383";
;
CDS_LIB"mstr_standard"
BODY_TYPE"PLUMBING"
HDL_TAP"TRUE";
"B \NAC \NWC"7;
"S \NAC"
BN"2"56;
%"TAP"
"1","(-3475,4025)","0","mstr_standard","I384";
;
CDS_LIB"mstr_standard"
BODY_TYPE"PLUMBING"
HDL_TAP"TRUE";
"B \NAC \NWC"7;
"S \NAC"
BN"3"52;
%"TAP"
"1","(-3475,3825)","0","mstr_standard","I385";
;
CDS_LIB"mstr_standard"
BODY_TYPE"PLUMBING"
HDL_TAP"TRUE";
"B \NAC \NWC"7;
"S \NAC"
BN"1"60;
%"TAP"
"1","(-3675,3975)","0","mstr_standard","I386";
;
CDS_LIB"mstr_standard"
BODY_TYPE"PLUMBING"
HDL_TAP"TRUE";
"B \NAC \NWC"8;
"S \NAC"
BN"2"55;
%"TAP"
"1","(-3675,3875)","0","mstr_standard","I387";
;
CDS_LIB"mstr_standard"
BODY_TYPE"PLUMBING"
HDL_TAP"TRUE";
"B \NAC \NWC"8;
"S \NAC"
BN"1"59;
%"TAP"
"1","(-3475,3575)","0","mstr_standard","I388";
;
CDS_LIB"mstr_standard"
BODY_TYPE"PLUMBING"
HDL_TAP"TRUE";
"B \NAC \NWC"9;
"S \NAC"
BN"9"34;
%"TAP"
"1","(-3475,3725)","0","mstr_standard","I389";
;
CDS_LIB"mstr_standard"
BODY_TYPE"PLUMBING"
HDL_TAP"TRUE";
"B \NAC \NWC"7;
"S \NAC"
BN"0"64;
%"TAP"
"1","(-3675,3775)","0","mstr_standard","I390";
;
CDS_LIB"mstr_standard"
BODY_TYPE"PLUMBING"
HDL_TAP"TRUE";
"B \NAC \NWC"8;
"S \NAC"
BN"0"63;
%"TAP"
"1","(-3675,3625)","0","mstr_standard","I391";
;
CDS_LIB"mstr_standard"
BODY_TYPE"PLUMBING"
HDL_TAP"TRUE";
"B \NAC \NWC"10;
"S \NAC"
BN"9"33;
%"TAP"
"1","(-3475,3475)","0","mstr_standard","I392";
;
CDS_LIB"mstr_standard"
BODY_TYPE"PLUMBING"
HDL_TAP"TRUE";
"B \NAC \NWC"9;
"S \NAC"
BN"8"66;
%"TAP"
"1","(-3475,3275)","0","mstr_standard","I393";
;
CDS_LIB"mstr_standard"
BODY_TYPE"PLUMBING"
HDL_TAP"TRUE";
"B \NAC \NWC"9;
"S \NAC"
BN"6"40;
%"TAP"
"1","(-3475,3375)","0","mstr_standard","I394";
;
CDS_LIB"mstr_standard"
BODY_TYPE"PLUMBING"
HDL_TAP"TRUE";
"B \NAC \NWC"9;
"S \NAC"
BN"7"37;
%"TAP"
"1","(-3675,3525)","0","mstr_standard","I395";
;
CDS_LIB"mstr_standard"
BODY_TYPE"PLUMBING"
HDL_TAP"TRUE";
"B \NAC \NWC"10;
"S \NAC"
BN"8"67;
%"TAP"
"1","(-3675,3425)","0","mstr_standard","I396";
;
CDS_LIB"mstr_standard"
BODY_TYPE"PLUMBING"
HDL_TAP"TRUE";
"B \NAC \NWC"10;
"S \NAC"
BN"7"65;
%"TAP"
"1","(-3675,3325)","0","mstr_standard","I397";
;
CDS_LIB"mstr_standard"
BODY_TYPE"PLUMBING"
HDL_TAP"TRUE";
"B \NAC \NWC"10;
"S \NAC"
BN"6"39;
%"TAP"
"1","(-3475,3075)","0","mstr_standard","I398";
;
CDS_LIB"mstr_standard"
BODY_TYPE"PLUMBING"
HDL_TAP"TRUE";
"B \NAC \NWC"9;
"S \NAC"
BN"4"47;
%"TAP"
"1","(-3475,3175)","0","mstr_standard","I399";
;
CDS_LIB"mstr_standard"
BODY_TYPE"PLUMBING"
HDL_TAP"TRUE";
"B \NAC \NWC"9;
"S \NAC"
BN"5"43;
%"TAP"
"1","(-3675,3225)","0","mstr_standard","I400";
;
CDS_LIB"mstr_standard"
BODY_TYPE"PLUMBING"
HDL_TAP"TRUE";
"B \NAC \NWC"10;
"S \NAC"
BN"5"42;
%"TAP"
"1","(-3675,3025)","0","mstr_standard","I401";
;
CDS_LIB"mstr_standard"
BODY_TYPE"PLUMBING"
HDL_TAP"TRUE";
"B \NAC \NWC"10;
"S \NAC"
BN"3"50;
%"TAP"
"1","(-3675,3125)","0","mstr_standard","I402";
;
CDS_LIB"mstr_standard"
BODY_TYPE"PLUMBING"
HDL_TAP"TRUE";
"B \NAC \NWC"10;
"S \NAC"
BN"4"46;
%"TAP"
"1","(-3475,2975)","0","mstr_standard","I403";
;
CDS_LIB"mstr_standard"
BODY_TYPE"PLUMBING"
HDL_TAP"TRUE";
"B \NAC \NWC"9;
"S \NAC"
BN"3"51;
%"TAP"
"1","(-3475,2775)","0","mstr_standard","I404";
;
CDS_LIB"mstr_standard"
BODY_TYPE"PLUMBING"
HDL_TAP"TRUE";
"B \NAC \NWC"9;
"S \NAC"
BN"1"58;
%"TAP"
"1","(-3475,2875)","0","mstr_standard","I405";
;
CDS_LIB"mstr_standard"
BODY_TYPE"PLUMBING"
HDL_TAP"TRUE";
"B \NAC \NWC"9;
"S \NAC"
BN"2"54;
%"TAP"
"1","(-3675,2925)","0","mstr_standard","I406";
;
CDS_LIB"mstr_standard"
BODY_TYPE"PLUMBING"
HDL_TAP"TRUE";
"B \NAC \NWC"10;
"S \NAC"
BN"2"53;
%"TAP"
"1","(-3675,2825)","0","mstr_standard","I407";
;
CDS_LIB"mstr_standard"
BODY_TYPE"PLUMBING"
HDL_TAP"TRUE";
"B \NAC \NWC"10;
"S \NAC"
BN"1"57;
%"TAP"
"1","(-3475,2675)","0","mstr_standard","I408";
;
CDS_LIB"mstr_standard"
BODY_TYPE"PLUMBING"
HDL_TAP"TRUE";
"B \NAC \NWC"9;
"S \NAC"
BN"0"62;
%"TAP"
"1","(-3675,2725)","0","mstr_standard","I409";
;
CDS_LIB"mstr_standard"
BODY_TYPE"PLUMBING"
HDL_TAP"TRUE";
"B \NAC \NWC"10;
"S \NAC"
BN"0"61;
%"SCONN288_DDR506112002KQ"
"2","(-4625,3675)","0","pure_quanta","I410";
;
LOCATION"J21"
$SEC"2"
CDS_SEC"2"
PART_TYPE"SMLF"
VALUE"SCONN288_DDR506112002KQ"
MATERIAL"IO"
PART_NUMBER"DFHST8FS479"
CDS_LMAN_SYM_OUTLINE"-600,1150,600,-1150"
NEEDS_NO_SIZE"TRUE"
CDS_LIB"pure_quanta";
"DQS7_A_C||TDQS7_A_C \B"
$PN"178"69;
"DQS6_A_T||TDQS6_A_T"
$PN"168"68;
"DQS8_B_T||TDQS8_B_T"
$PN"283"67;
"DQS8_B_C||TDQS8_B_C \B"
$PN"282"66;
"DQS7_B_T||TDQS7_B_T"
$PN"272"65;
"DQS0_A_C \B"
$PN"12"64;
"DQS0_A_T"
$PN"11"63;
"DQS0_B_C \B"
$PN"105"62;
"DQS0_B_T"
$PN"104"61;
"DQS1_A_C \B"
$PN"23"60;
"DQS1_A_T"
$PN"22"59;
"DQS1_B_C \B"
$PN"116"58;
"DQS1_B_T"
$PN"115"57;
"DQS2_A_C \B"
$PN"34"56;
"DQS2_A_T"
$PN"33"55;
"DQS2_B_C \B"
$PN"127"54;
"DQS2_B_T"
$PN"126"53;
"DQS3_A_C \B"
$PN"45"52;
"DQS3_A_T"
$PN"44"29;
"DQS3_B_C \B"
$PN"138"51;
"DQS3_B_T"
$PN"137"50;
"DQS4_A_C \B"
$PN"56"49;
"DQS4_A_T"
$PN"55"48;
"DQS4_B_C \B"
$PN"238"47;
"DQS4_B_T"
$PN"239"46;
"DQS5_A_C||TDQS5_A_C||DQS5_A_T||TDQS5_A_T \B"
$PN"156"45;
"DQS5_A_T||TDQS5_A_T"
$PN"157"44;
"DQS5_B_C||TDQS5_B_C \B"
$PN"249"43;
"DQS5_B_T||TDQS5_B_T"
$PN"250"42;
"DQS6_A_C||TDQS6_A_C||DQS6_A_T||TDQS6_A_T \B"
$PN"167"41;
"DQS6_B_C||TDQS6_B_C \B"
$PN"260"40;
"DQS6_B_T||TDQS6_B_T"
$PN"261"39;
"DQS7_A_T||TDQS7_A_T"
$PN"179"38;
"DQS7_B_C||TDQS7_B_C \B"
$PN"271"37;
"DQS8_A_C||TDQS8_A_C \B"
$PN"189"36;
"DQS8_A_T||TDQS8_A_T"
$PN"190"35;
"DQS9_A_C||TDQS9_A_C \B"
$PN"200"31;
"DQS9_A_T||TDQS9_A_T"
$PN"201"32;
"DQS9_B_C||TDQS9_B_C \B"
$PN"94"34;
"DQS9_B_T||TDQS9_B_T||DBI4_B_N"
$PN"93"33;
%"GND"
"1","(-2975,5700)","0","pure_quanta_power","I411";
;
CDS_LIB"pure_quanta_power"
BOM_COST"MEM"
SIZE"1B"
ROOM"MEM_EFGH_DECOUPLING_CAPS"
HDL_POWER"GND";
"A<SIZE-1..0>\NAC"178;
%"Q_CAP"
"1","(-2975,6050)","2","pure_quanta","I412";
;
LOCATION"C151"
$SEC"1"
CDS_SEC"1"
MATERIAL"X6S"
TOLERANCE"10%"
VALUE"10UF"
PART_NUMBER"CH6104KEA00"
VOLTAGE"25V"
PACK_TYPE"C0805"
BOM_COST"MEM"
CDS_LIB"pure_quanta"
ROOM"MEM_CH_A_CPU0_DIMM1";
"B"
$PN"2"178;
"A"
$PN"1"28;
%"Q_CAP"
"1","(-2400,6050)","2","pure_quanta","I413";
;
LOCATION"C153"
$SEC"1"
CDS_SEC"1"
MATERIAL"X6S"
TOLERANCE"10%"
VALUE"10UF"
PART_NUMBER"CH6104KEA00"
VOLTAGE"25V"
PACK_TYPE"C0805"
BOM_COST"MEM"
CDS_LIB"pure_quanta"
ROOM"MEM_CH_A_CPU0_DIMM1";
"B"
$PN"2"178;
"A"
$PN"1"28;
%"UNIVERSAL_POWER"
"1","(-2975,6375)","0","pure_quanta_power","I414";
;
HDL_POWER"P12V_MEM_1"
BOM_COST"VR_SYSTEM"
CDS_LIB"pure_quanta_power";
"A"28;
%"Q_RES"
"1","(-8025,2875)","0","pure_quanta","I416";
;
$LOCATION"R1572"
CDS_LOCATION"R1572"
$SEC"1"
CDS_SEC"1"
VALUE"49.9"
PART_NUMBER"CS04992FB07"
TOLERANCE"1%"
WATTAGE"1/16W"
PACK_TYPE"0402LF"
MATERIAL"CHIP"
CDS_LIB"pure_quanta";
"B"
$PN"2"17;
"A"
$PN"1"16;
END.
